# BASEBOARD_FAB2 (Tioga Pass) — schematic netlist excerpt (pin names and nets, part order shuffled) for the footprints in the layout excerpt that follows; sources: Cadence DE-HDL packaged netlist, KiCad conversion of Wiwynn_Tioga_Pass_MB.brd

C2L25  CAPP  470UF 2V 20% ALUM  pkg SM  page 236 : A = P1V05_PCH_STBY ; B = GND
R7D6  RES  4.75K 1% CHIP  pkg 0402  page 133 : A = P3V3_STBY ; B = FM_BMC_READY_N
C22W24  SC22U16V5MX-4-GP  20%  pkg SMD-BCG5  page 236 : \1\ = VR_FET_SW_P12V_STBY_PVDDQ_DEF ; \2\ = GND

(kicad_pcb
	(version 20260206)
	(generator "pcbnew")
	(generator_version "10.0")
	(general
		(thickness 1.6)
		(legacy_teardrops no)
	)
	(paper "A4")
	(title_block
		(title "Wiwynn_Tioga_Pass_MB.brd")
		(comment 1 "Tioga Pass / footprints 4312-4314 of 4770")
	)
	(layers
		(0 "F.Cu" signal "TOP")
		(4 "In1.Cu" signal "L2GND")
		(6 "In2.Cu" signal "L3")
		(8 "In3.Cu" signal "L4GND")
		(10 "In4.Cu" signal "L5")
		(12 "In5.Cu" signal "L6GND")
		(14 "In6.Cu" signal "L7VCC")
		(16 "In7.Cu" signal "L8VCC")
		(18 "In8.Cu" signal "L9GND")
		(20 "In9.Cu" signal "L10")
		(22 "In10.Cu" signal "L11GND")
		(24 "In11.Cu" signal "L12")
		(26 "In12.Cu" signal "L13GND")
		(2 "B.Cu" signal "BOTTOM")
		(9 "F.Adhes" user "F.Adhesive")
		(11 "B.Adhes" user "B.Adhesive")
		(13 "F.Paste" user "Package Geometry/Pastemask Top")
		(15 "B.Paste" user "Package Geometry/Pastemask Bottom")
		(5 "F.SilkS" user "Ref Des/Silkscreen Top")
		(7 "B.SilkS" user "Ref Des/Silkscreen Bottom")
		(1 "F.Mask" user "Board Geometry/Soldermask Top")
		(3 "B.Mask" user "Board Geometry/Soldermask Bottom")
		(17 "Dwgs.User" user "User.Drawings")
		(19 "Cmts.User" user "User.Comments")
		(21 "Eco1.User" user "User.Eco1")
		(23 "Eco2.User" user "User.Eco2")
		(25 "Edge.Cuts" user "Board Geometry/Outline")
		(27 "Margin" user)
		(31 "F.CrtYd" user "Package Geometry/Place Bound Top")
		(29 "B.CrtYd" user "Package Geometry/Place Bound Bottom")
		(35 "F.Fab" user "Ref Des/Assembly Top")
		(33 "B.Fab" user "Ref Des/Assembly Bottom")
	)
	(footprint ""
		(layer "B.Cu")
		(at 382.27 -87.3125 180)
		(property "Reference" "R7D6"
			(at 0 0 0)
			(layer "B.SilkS")
			(hide yes)
			(effects
				(font
					(size 1.27 1.27)
				)
				(justify mirror)
			)
		)
		(property "Value" ""
			(at 0 0 0)
			(layer "B.Fab")
			(effects
				(font
					(size 1.27 1.27)
				)
				(justify mirror)
			)
		)
		(duplicate_pad_numbers_are_jumpers no)
		(fp_poly
			(pts
				(xy 0.2794 -0.1016) (xy -0.2794 -0.1016) (xy -0.2794 0.9906) (xy 0.2794 0.9906)
			)
			(stroke
				(width 0)
				(type default)
			)
			(fill no)
			(layer "B.CrtYd")
		)
		(fp_line
			(start 0.2794 0.9906)
			(end -0.2794 0.9906)
			(stroke
				(width 0.1)
				(type default)
			)
			(layer "B.Fab")
		)
		(fp_line
			(start 0.2794 -0.1016)
			(end 0.2794 0.9906)
			(stroke
				(width 0.1)
				(type default)
			)
			(layer "B.Fab")
		)
		(fp_line
			(start -0.2794 0.9906)
			(end -0.2794 -0.1016)
			(stroke
				(width 0.1)
				(type default)
			)
			(layer "B.Fab")
		)
		(fp_line
			(start -0.2794 -0.1016)
			(end 0.2794 -0.1016)
			(stroke
				(width 0.1)
				(type default)
			)
			(layer "B.Fab")
		)
		(pad "1" smd rect
			(at 0 0)
			(size 0.508 0.508)
			(layers "B.Cu" "B.Mask" "B.Paste")
			(net "P3V3_STBY")
		)
		(pad "2" smd rect
			(at 0 0.889)
			(size 0.508 0.508)
			(layers "B.Cu" "B.Mask" "B.Paste")
			(net "FM_BMC_READY_N")
		)
		(zone
			(layer "B.Cu")
			(hatch none 0.5)
			(connect_pads
				(clearance 0)
			)
			(min_thickness 0.25)
			(keepout
				(tracks not_allowed)
				(vias allowed)
				(pads allowed)
				(copperpour not_allowed)
				(footprints allowed)
			)
			(placement
				(enabled no)
				(sheetname "")
			)
			(fill
				(thermal_gap 0.5)
				(thermal_bridge_width 0.5)
				(island_removal_mode 0)
			)
			(polygon
				(pts
					(xy 382.016 -87.9475) (xy 382.524 -87.9475) (xy 382.524 -87.5665) (xy 382.016 -87.5665)
				)
			)
		)
		(zone
			(layer "B.Cu")
			(hatch none 0.5)
			(connect_pads
				(clearance 0)
			)
			(min_thickness 0.25)
			(keepout
				(tracks allowed)
				(vias not_allowed)
				(pads allowed)
				(copperpour not_allowed)
				(footprints allowed)
			)
			(placement
				(enabled no)
				(sheetname "")
			)
			(fill
				(thermal_gap 0.5)
				(thermal_bridge_width 0.5)
				(island_removal_mode 0)
			)
			(polygon
				(pts
					(xy 382.016 -87.5665) (xy 382.524 -87.5665) (xy 382.524 -87.9475) (xy 382.016 -87.9475)
				)
			)
		)
	)
	(footprint ""
		(layer "B.Cu")
		(at 370.967 -152.019 90)
		(property "Reference" "C22W24"
			(at 0 0 90)
			(layer "B.SilkS")
			(hide yes)
			(effects
				(font
					(size 1.27 1.27)
				)
				(justify mirror)
			)
		)
		(property "Value" "*"
			(at 0.0762 -6.2357 90)
			(unlocked yes)
			(layer "B.Fab")
			(hide yes)
			(effects
				(font
					(size 1.27 1.016)
					(thickness 0.1524)
				)
				(justify mirror)
			)
		)
		(property "Device Type" "SC22U16V5MX-4-GP_SMD-BCG5-SC22A"
			(at 0.0762 -8.2677 90)
			(unlocked yes)
			(layer "B.Fab")
			(hide yes)
			(effects
				(font
					(size 1.27 1.016)
					(thickness 0.1524)
				)
				(justify mirror)
			)
		)
		(duplicate_pad_numbers_are_jumpers no)
		(fp_line
			(start -0.635 0)
			(end 0.635 0)
			(stroke
				(width 0.508)
				(type default)
			)
			(layer "B.SilkS")
		)
		(fp_rect
			(start 0.9652 1.778)
			(end -0.9652 -1.778)
			(stroke
				(width 0)
				(type default)
			)
			(fill no)
			(layer "B.CrtYd")
		)
		(fp_poly
			(pts
				(xy 0.9652 -1.778) (xy -0.9652 -1.778) (xy -0.9652 1.778) (xy 0.9652 1.778)
			)
			(stroke
				(width 0)
				(type default)
			)
			(fill no)
			(layer "B.Fab")
		)
		(pad "1" smd rect
			(at 0 -0.9652 270)
			(size 1.397 1.143)
			(layers "B.Cu" "B.Mask" "B.Paste")
			(net "VR_FET_SW_P12V_STBY_PVDDQ_DEF")
		)
		(pad "2" smd rect
			(at 0 0.9652 270)
			(size 1.397 1.143)
			(layers "B.Cu" "B.Mask" "B.Paste")
			(net "GND")
		)
	)
	(footprint ""
		(layer "B.Cu")
		(at 391.18794 -139.66698 180)
		(property "Reference" "C2L25"
			(at -3.10007 3.24612 270)
			(unlocked yes)
			(layer "B.SilkS")
			(effects
				(font
					(size 0.7874 0.5842)
					(thickness 0.1524)
				)
				(justify mirror)
			)
		)
		(property "Value" ""
			(at 0 0 0)
			(layer "B.Fab")
			(effects
				(font
					(size 1.27 1.27)
				)
				(justify mirror)
			)
		)
		(duplicate_pad_numbers_are_jumpers no)
		(fp_line
			(start 2.563114 1.633728)
			(end 1.6002 1.633728)
			(stroke
				(width 0.1524)
				(type default)
			)
			(layer "B.SilkS")
		)
		(fp_line
			(start 2.563114 -1.616456)
			(end 2.563114 1.633728)
			(stroke
				(width 0.1524)
				(type default)
			)
			(layer "B.SilkS")
		)
		(fp_line
			(start 2.286 7.366)
			(end 2.286 1.632712)
			(stroke
				(width 0.1524)
				(type default)
			)
			(layer "B.SilkS")
		)
		(fp_line
			(start 2.286 7.366)
			(end 1.60147 7.366)
			(stroke
				(width 0.1524)
				(type default)
			)
			(layer "B.SilkS")
		)
		(fp_line
			(start 1.6002 -1.616456)
			(end 2.563114 -1.616456)
			(stroke
				(width 0.1524)
				(type default)
			)
			(layer "B.SilkS")
		)
		(fp_line
			(start -1.6002 -1.616456)
			(end -2.504948 -1.616456)
			(stroke
				(width 0.1524)
				(type default)
			)
			(layer "B.SilkS")
		)
		(fp_line
			(start -2.286 7.366)
			(end -1.600708 7.366)
			(stroke
				(width 0.1524)
				(type default)
			)
			(layer "B.SilkS")
		)
		(fp_line
			(start -2.286 7.366)
			(end -2.286 1.63195)
			(stroke
				(width 0.1524)
				(type default)
			)
			(layer "B.SilkS")
		)
		(fp_line
			(start -2.504948 1.633728)
			(end -1.6002 1.633728)
			(stroke
				(width 0.1524)
				(type default)
			)
			(layer "B.SilkS")
		)
		(fp_line
			(start -2.504948 -1.616456)
			(end -2.504948 1.633728)
			(stroke
				(width 0.1524)
				(type default)
			)
			(layer "B.SilkS")
		)
		(fp_rect
			(start 2.286 7.366)
			(end -2.286 -0.254)
			(stroke
				(width 0)
				(type default)
			)
			(fill no)
			(layer "B.CrtYd")
		)
		(fp_line
			(start 2.286 7.366)
			(end 2.286 -0.254)
			(stroke
				(width 0.1)
				(type default)
			)
			(layer "B.Fab")
		)
		(fp_line
			(start 2.286 -0.254)
			(end -2.286 -0.254)
			(stroke
				(width 0.1)
				(type default)
			)
			(layer "B.Fab")
		)
		(fp_line
			(start -2.286 7.366)
			(end 2.286 7.366)
			(stroke
				(width 0.1)
				(type default)
			)
			(layer "B.Fab")
		)
		(fp_line
			(start -2.286 -0.254)
			(end -2.286 7.366)
			(stroke
				(width 0.1)
				(type default)
			)
			(layer "B.Fab")
		)
		(pad "1" smd rect
			(at 0 0)
			(size 2.54 3.048)
			(layers "B.Cu" "B.Mask" "B.Paste")
			(net "P1V05_PCH_STBY")
		)
		(pad "2" smd rect
			(at 0 7.112)
			(size 2.54 3.048)
			(layers "B.Cu" "B.Mask" "B.Paste")
			(net "GND")
		)
	)
)
